# SCM (Grand Teton) — schematic netlist excerpt (pin names and nets, part order shuffled) for the footprints in the layout excerpt that follows; sources: Cadence DE-HDL packaged netlist, KiCad conversion of 12092022_DA0F0TMDCD0_F0T_Management_Board_D_brd_V3_OCP.brd

GF1  FCONN168_ME1016810202011_SCM  EMPTY  pkg GOLD_168P_ME1016813401311  page 10
  I2C_0_SCL  = SMB_BMC_MM14_R1_SCL
  I2C_0_SDA  = SMB_BMC_MM14_R1_SDA
  I2C_1_SCL  = SMB_BMC_MM1_SCL
  I2C_1_SDA  = SMB_BMC_MM1_SDA
  I2C_2_SCL  = SMB_BMC_MM2_SCL_R1
  I2C_2_SDA  = SMB_BMC_MM2_SDA
  I2C_3_SCL  = SMB_BMC_MM3_SCL
  I2C_3_SDA  = SMB_BMC_MM3_SDA
  I2C_4_SCL  = SMB_BMC_MM4_SCL
  I2C_4_SDA  = SMB_BMC_MM4_SDA
  I2C_5_SCL  = SMB_BMC_MM5_SCL
  I2C_5_SDA  = SMB_BMC_MM5_SDA
  GND_A13  = GND
  CLK_100M_PCIE_DP  = CLK_100M_PCH_DP
  CLK_100M_PCIE_DN  = CLK_100M_PCH_DN
  GND_A16  = GND
  PCIE_BMC_TX_DP  = P2E_PCH_RX_DP
  PCIE_BMC_TX_DN  = P2E_PCH_RX_DN
  GND_A19  = GND
  PCIE_BMC_RX_DP  = P2E_PCH_TX_C_DP
  PCIE_BMC_RX_DN  = P2E_PCH_TX_C_DN
  GND_A22  = GND
  I2C_6_SCL  = SMB_BMC_MM6_SCL
  I2C_6_SDA  = SMB_BMC_MM6_SDA
  I2C_7_SCL  = SMB_BMC_MM7_SCL
  I2C_7_SDA  = SMB_BMC_MM7_SDA
  I2C_8_SCL  = SMB_BMC_MM8_SCL
  I2C_8_SDA  = SMB_BMC_MM8_SDA
  I2C_9_SCL  = SMB_BMC_MM9_SCL
  I2C_9_SDA  = SMB_BMC_MM9_SDA
  I2C_10_SCL  = SMB_BMC_MM10_SCL
  I2C_10_SDA  = SMB_BMC_MM10_SDA
  GND_A33  = GND
  JTAG_TCK  = JTAG_MB_TCK
  JTAG_TMS  = JTAG_MB_TMS
  JTAG_TDI  = JTAG_MB_TDI
  JTAG_TDO  = JTAG_MB_TDO
  I2C_11_SCL  = SMB_BMC_MM12_SCL
  I2C_11_SDA  = SMB_BMC_MM12_SDA
  I2C_12_SCL  = SMB_BMC_MM13_SCL
  I2C_12_SDA  = SMB_BMC_MM13_SDA
  GND_A42  = GND
  HPM_FW_RECOVERY  = FM_JTAG_SEL
  HPM_STBY_RDY  = PWRGD_PSU_AC_PWROK_R
  HPM_STBY_EN  = TP_GF_A45
  HPM_STBY_RST_N  = RST_MB_STBY_N
  SYS_PWRBTN_N  = SYS_PWRBTN_N
  SYS_PWROK  = PWRGD_SYS_PWROK
  DBP_PREQ_N  = FM_DBP_CPU_PREQ_GF_R_N
  DBP_PRDY_N  = FM_DBP_BMC_PRDY_N
  RST_PLTRST_BUF_N  = RST_PLTRST_N
  SPARE1  = FM_BMC_UARTSW_MSB_N
  ROT_CPU_RST_N  = RST_ROT_CPU_N
  CHASI_N  = FM_INTRUDER_N
  SPARE0  = FM_BMC_UARTSW_LSB_N
  IRQ_N  = IRQ_SMI_ACTIVE_GF_N
  PRSNT1_N  = FM_PRSNT_1_N
  GND_A58  = GND
  PCIE_HPM_RXP_0  = USB3_FPNL_RXP
  PCIE_HPM_RXN_0  = USB3_FPNL_RXN
  GND_A61  = GND
  PCIE_HPM_RXP_1  = TP_GF_A62
  PCIE_HPM_RXN_1  = TP_GF_A63
  GND_A64  = GND
  PCIE_HPM_RXP_2  = P2E_GPU_RX_DP
  PCIE_HPM_RXN_2  = P2E_GPU_RX_DN
  GND_A67  = GND
  PCIE_HPM_RXP_3  = CLK_100M_GPU_DP
  PCIE_HPM_RXN_3  = CLK_100M_GPU_DN
  GND_A70  = GND
  ESPI_CLK  = ESPI_HOST_LPC_BMC_CLK
  ESPI_CS0_N  = ESPI_HOST_LPC_BMC_LFRAME_N
  ESPI_ALERT_N  = IRQ_BMC_LPC_SERIRQ_ESPI_GF
  ESPI_RESET_N  = RST_BMC_LPC_ESPI_N
  ESPI_IO0  = ESPI_LPC_LAD0_IO0
  ESPI_IO1  = ESPI_LPC_LAD1_IO1
  ESPI_IO2  = ESPI_LPC_LAD2_IO2
  ESPI_IO3  = ESPI_LPC_LAD3_IO3
  RSVD3  = LPC_ESPI_SEL
  GND_B10  = GND
  QSPI0_CLK  = SPI_SYS_R_CLK
  QSPI0_CS0_N  = SPI_SYS_CS0_N
  QSPI0_D0  = SPI_SYS_R_MOSI
  QSPI0_D1  = SPI_SYS_R_MISO
  QSPI0_D2  = SPI_SYS_WP_R_IO2
  QSPI0_D3  = SPI_SYS_HOLD_R_IO3
  GND_B17  = GND
  NCSI_CLK  = RMII_OCP_RCLKI
  NCSI_CRS_DV  = RMII_CSRDV
  NCSI_TXEN  = RMII_TXEN
  NCSI_TXD0  = RMII_TXD0
  NCSI_TXD1  = RMII_TXD1
  NCSI_RXER  = RMII_RXER
  NCSI_RXD0  = RMII_RXD0
  NCSI_RXD1  = RMII_RXD1
  GND_B26  = GND
  PECI_BMC  = PECI_BMC
  PVCCIO_PECI  = PVCCIO_PECI_BMC
  SGPIO0_DO  = SGPIO_DO_0
  SGPIO_CLK  = SGPIO_CLK_0
  SGPIO0_DI  = SGPIO_DI_0
  SGPIO0_LD  = SGPIO_LD_0
  GND_B33  = GND
  SGPIO1_DO  = SGPIO_DO_1
  RSVD2  = SGPIO_CLK_1
  SGPIO1_DI  = SGPIO_DI_1
  SGPIO1_LD  = SGPIO_LD_1
  GND_B38  = GND
  SGPIO_RESET_N  = RST_SGPIO_RESET_N
  SGPIO_INTR_N  = IRQ_SGPIO_N
  P3V0_BAT  = P3V_BAT_R
  QSPI0_CS1_N  = AC_PWR_BTN_N
  QSPI1_CLK  = QSPI_2_PLD_CLK
  QSPI1_CS0_N  = TP_GF1_B44
  QSPI1_D0  = QSPI_2_PLD_IO0
  QSPI1_D1  = QSPI_2_PLD_IO1
  QSPI1_D2  = QSPI_2_PLD_IO2
  QSPI1_D3  = QSPI_2_PLD_IO3
  GND_B49  = GND
  USB2_DP  = USB_HOST_BMC_B_DP
  USB2_DN  = USB_HOST_BMC_B_DN
  GND_B52  = GND
  USB1_DP  = USB_HOST_BMC_A_DP
  USB1_DN  = USB_HOST_BMC_A_DN
  GND_B55  = GND
  RSVD0  = USB_FPNL_DP
  RSVD1  = USB_FPNL_DN
  GND_B58  = GND
  PCIE_HPM_TXP_0  = USB3_FPNL_TXP
  PCIE_HPM_TXN_0  = USB3_FPNL_TXN
  GND_B61  = GND
  PCIE_HPM_TXP_1  = TP_GF_B62
  PCIE_HPM_TXN_1  = TP_GF_B63
  GND_B64  = GND
  PCIE_HPM_TXP_2  = P2E_GPU_TX_C_DP
  PCIE_HPM_TXN_2  = P2E_GPU_TX_C_DN
  GND_B67  = GND
  PCIE_HPM_TXP_3  = HDD_LED_R_N
  PCIE_HPM_TXN_3  = PCH_BEEP_R_LED
  GND_B70  = GND
  P12V_AUX_OA1  = P12V_AUX
  P12V_AUX_OA2  = P12V_AUX
  GND_OA3  = GND
  GND_OA4  = GND
  I3C_0_SCL  = I3C1_SPD_SCL
  I3C_0_SDA  = I3C1_SPD_SDA
  I3C_1_SCL  = I3C2_SPD_SCL
  I3C_1_SDA  = I3C2_SPD_SDA
  I3C_2_SCL  = I3C3_SPD_SCL
  I3C_2_SDA  = I3C3_SPD_SDA
  I3C_3_SCL  = I3C4_SPD_SCL
  I3C_3_SDA  = I3C4_SPD_SDA
  GND_OA13  = GND
  VIRTUAL_RESEAT  = FM_VIRTUAL_RESEAT
  P12V_AUX_OB1  = P12V_AUX
  P12V_AUX_OB2  = P12V_AUX
  PRSNT0_N  = FM_PRSNT_0_R_N
  GND_OB4  = GND
  UART1_SCM_TX  = UART_BIC_GF_TXD
  UART1_SCM_RX  = UART_BIC_GF_RXD
  GND_OB7  = GND
  UART0_SCM_TX  = UART_SYS_DBG_TX
  UART0_SCM_RX  = UART_SYS_DBG_RX
  GND_OB10  = GND
  SPI0_CLK  = RST_SRST_PLD_BMC_R_N
  SPI0_CS_N  = SPI_TPM_CS_N
  SPI0_MOSI  = H_CPU_CATERR_LVC2_R2_N
  SPI0_MISO  = FM_SOL_UART_CH_SEL

(kicad_pcb
	(version 20260206)
	(generator "pcbnew")
	(generator_version "10.0")
	(general
		(thickness 1.6)
		(legacy_teardrops no)
	)
	(paper "A4")
	(title_block
		(title "12092022_DA0F0TMDCD0_F0T_Management_Board_D_brd_V3_OCP.brd")
		(comment 1 "Grand Teton / footprint 804 of 1440 (GF1), pads 96-144 of 168")
	)
	(layers
		(0 "F.Cu" signal "TOP")
		(4 "In1.Cu" signal "GND")
		(6 "In2.Cu" signal "IN1")
		(8 "In3.Cu" signal "GND1")
		(10 "In4.Cu" signal "IN2")
		(12 "In5.Cu" signal "VCC")
		(14 "In6.Cu" signal "VCC1")
		(16 "In7.Cu" signal "IN3")
		(18 "In8.Cu" signal "GND2")
		(20 "In9.Cu" signal "IN4")
		(22 "In10.Cu" signal "GND3")
		(2 "B.Cu" signal "BOTTOM")
		(9 "F.Adhes" user "F.Adhesive")
		(11 "B.Adhes" user "B.Adhesive")
		(13 "F.Paste" user "Package Geometry/Pastemask Top")
		(15 "B.Paste" user "Package Geometry/Pastemask Bottom")
		(5 "F.SilkS" user "Ref Des/Silkscreen Top")
		(7 "B.SilkS" user "Ref Des/Silkscreen Bottom")
		(1 "F.Mask" user "Board Geometry/Soldermask Top")
		(3 "B.Mask" user "Board Geometry/Soldermask Bottom")
		(17 "Dwgs.User" user "User.Drawings")
		(19 "Cmts.User" user "User.Comments")
		(21 "Eco1.User" user "User.Eco1")
		(23 "Eco2.User" user "User.Eco2")
		(25 "Edge.Cuts" user "Board Geometry/Outline")
		(27 "Margin" user)
		(31 "F.CrtYd" user "Package Geometry/Place Bound Top")
		(29 "B.CrtYd" user "Package Geometry/Place Bound Bottom")
		(35 "F.Fab" user "Ref Des/Assembly Top")
		(33 "B.Fab" user "Ref Des/Assembly Bottom")
	)
	(footprint ""
		(layer "B.Cu")
		(at 45.260006 -114.324892 180)
		(property "Reference" "GF1"
			(at 30.591506 -4.763262 0)
			(unlocked yes)
			(layer "B.SilkS")
			(effects
				(font
					(size 0.7874 0.5842)
					(thickness 0.1524)
				)
				(justify left mirror)
			)
		)
		(property "Value" ""
			(at 0 0 0)
			(layer "B.Fab")
			(effects
				(font
					(size 1.27 1.27)
				)
				(justify mirror)
			)
		)
		(duplicate_pad_numbers_are_jumpers no)
		(pad "B26" smd rect
			(at -3.204972 3.934968)
			(size 0.381 1.7272)
			(layers "B.Cu" "B.Mask" "B.Paste")
			(net "GND")
		)
		(pad "B27" smd rect
			(at -2.605024 3.934968)
			(size 0.381 1.7272)
			(layers "B.Cu" "B.Mask" "B.Paste")
			(net "PECI_BMC")
		)
		(pad "B28" smd rect
			(at -2.005076 4.13512)
			(size 0.381 2.1336)
			(layers "B.Cu" "B.Mask" "B.Paste")
			(net "PVCCIO_PECI_BMC")
		)
		(pad "B29" smd rect
			(at 2.005076 4.13512)
			(size 0.381 2.1336)
			(layers "B.Cu" "B.Mask" "B.Paste")
			(net "SGPIO_DO_0")
		)
		(pad "B30" smd rect
			(at 2.605024 3.934968)
			(size 0.381 1.7272)
			(layers "B.Cu" "B.Mask" "B.Paste")
			(net "SGPIO_CLK_0")
		)
		(pad "B31" smd rect
			(at 3.204972 3.934968)
			(size 0.381 1.7272)
			(layers "B.Cu" "B.Mask" "B.Paste")
			(net "SGPIO_DI_0")
		)
		(pad "B32" smd rect
			(at 3.80492 4.13512)
			(size 0.381 2.1336)
			(layers "B.Cu" "B.Mask" "B.Paste")
			(net "SGPIO_LD_0")
		)
		(pad "B33" smd rect
			(at 4.405122 3.934968)
			(size 0.381 1.7272)
			(layers "B.Cu" "B.Mask" "B.Paste")
			(net "GND")
		)
		(pad "B34" smd rect
			(at 5.00507 3.934968)
			(size 0.381 1.7272)
			(layers "B.Cu" "B.Mask" "B.Paste")
			(net "SGPIO_DO_1")
		)
		(pad "B35" smd rect
			(at 5.605018 4.13512)
			(size 0.381 2.1336)
			(layers "B.Cu" "B.Mask" "B.Paste")
			(net "SGPIO_CLK_1")
		)
		(pad "B36" smd rect
			(at 6.204966 3.934968)
			(size 0.381 1.7272)
			(layers "B.Cu" "B.Mask" "B.Paste")
			(net "SGPIO_DI_1")
		)
		(pad "B37" smd rect
			(at 6.804914 3.934968)
			(size 0.381 1.7272)
			(layers "B.Cu" "B.Mask" "B.Paste")
			(net "SGPIO_LD_1")
		)
		(pad "B38" smd rect
			(at 7.405116 4.13512)
			(size 0.381 2.1336)
			(layers "B.Cu" "B.Mask" "B.Paste")
			(net "GND")
		)
		(pad "B39" smd rect
			(at 8.005064 3.934968)
			(size 0.381 1.7272)
			(layers "B.Cu" "B.Mask" "B.Paste")
			(net "RST_SGPIO_RESET_N")
		)
		(pad "B40" smd rect
			(at 8.605012 3.934968)
			(size 0.381 1.7272)
			(layers "B.Cu" "B.Mask" "B.Paste")
			(net "IRQ_SGPIO_N")
		)
		(pad "B41" smd rect
			(at 9.20496 4.13512)
			(size 0.381 2.1336)
			(layers "B.Cu" "B.Mask" "B.Paste")
			(net "P3V_BAT_R")
		)
		(pad "B42" smd rect
			(at 9.804908 4.13512)
			(size 0.381 2.1336)
			(layers "B.Cu" "B.Mask" "B.Paste")
			(net "AC_PWR_BTN_N")
		)
		(pad "B43" smd rect
			(at 14.714982 4.13512)
			(size 0.381 2.1336)
			(layers "B.Cu" "B.Mask" "B.Paste")
			(net "QSPI_2_PLD_CLK")
		)
		(pad "B44" smd rect
			(at 15.31493 3.934968)
			(size 0.381 1.7272)
			(layers "B.Cu" "B.Mask" "B.Paste")
			(net "TP_GF1_B44")
		)
		(pad "B45" smd rect
			(at 15.914878 3.934968)
			(size 0.381 1.7272)
			(layers "B.Cu" "B.Mask" "B.Paste")
			(net "QSPI_2_PLD_IO0")
		)
		(pad "B46" smd rect
			(at 16.51508 4.13512)
			(size 0.381 2.1336)
			(layers "B.Cu" "B.Mask" "B.Paste")
			(net "QSPI_2_PLD_IO1")
		)
		(pad "B47" smd rect
			(at 17.115028 3.934968)
			(size 0.381 1.7272)
			(layers "B.Cu" "B.Mask" "B.Paste")
			(net "QSPI_2_PLD_IO2")
		)
		(pad "B48" smd rect
			(at 17.714976 3.934968)
			(size 0.381 1.7272)
			(layers "B.Cu" "B.Mask" "B.Paste")
			(net "QSPI_2_PLD_IO3")
		)
		(pad "B49" smd rect
			(at 18.314924 4.13512)
			(size 0.381 2.1336)
			(layers "B.Cu" "B.Mask" "B.Paste")
			(net "GND")
		)
		(pad "B50" smd rect
			(at 18.914872 3.934968)
			(size 0.381 1.7272)
			(layers "B.Cu" "B.Mask" "B.Paste")
			(net "USB_HOST_BMC_B_DP")
		)
		(pad "B51" smd rect
			(at 19.515074 3.934968)
			(size 0.381 1.7272)
			(layers "B.Cu" "B.Mask" "B.Paste")
			(net "USB_HOST_BMC_B_DN")
		)
		(pad "B52" smd rect
			(at 20.115022 4.13512)
			(size 0.381 2.1336)
			(layers "B.Cu" "B.Mask" "B.Paste")
			(net "GND")
		)
		(pad "B53" smd rect
			(at 20.71497 3.934968)
			(size 0.381 1.7272)
			(layers "B.Cu" "B.Mask" "B.Paste")
			(net "USB_HOST_BMC_A_DP")
		)
		(pad "B54" smd rect
			(at 21.314918 3.934968)
			(size 0.381 1.7272)
			(layers "B.Cu" "B.Mask" "B.Paste")
			(net "USB_HOST_BMC_A_DN")
		)
		(pad "B55" smd rect
			(at 21.91512 4.13512)
			(size 0.381 2.1336)
			(layers "B.Cu" "B.Mask" "B.Paste")
			(net "GND")
		)
		(pad "B56" smd rect
			(at 22.515068 3.934968)
			(size 0.381 1.7272)
			(layers "B.Cu" "B.Mask" "B.Paste")
			(net "USB_FPNL_DP")
		)
		(pad "B57" smd rect
			(at 23.115016 3.934968)
			(size 0.381 1.7272)
			(layers "B.Cu" "B.Mask" "B.Paste")
			(net "USB_FPNL_DN")
		)
		(pad "B58" smd rect
			(at 23.714964 4.13512)
			(size 0.381 2.1336)
			(layers "B.Cu" "B.Mask" "B.Paste")
			(net "GND")
		)
		(pad "B59" smd rect
			(at 24.314912 3.934968)
			(size 0.381 1.7272)
			(layers "B.Cu" "B.Mask" "B.Paste")
			(net "USB3_FPNL_TXP")
		)
		(pad "B60" smd rect
			(at 24.915114 3.934968)
			(size 0.381 1.7272)
			(layers "B.Cu" "B.Mask" "B.Paste")
			(net "USB3_FPNL_TXN")
		)
		(pad "B61" smd rect
			(at 25.515062 4.13512)
			(size 0.381 2.1336)
			(layers "B.Cu" "B.Mask" "B.Paste")
			(net "GND")
		)
		(pad "B62" smd rect
			(at 26.11501 3.934968)
			(size 0.381 1.7272)
			(layers "B.Cu" "B.Mask" "B.Paste")
			(net "TP_GF_B62")
		)
		(pad "B63" smd rect
			(at 26.714958 3.934968)
			(size 0.381 1.7272)
			(layers "B.Cu" "B.Mask" "B.Paste")
			(net "TP_GF_B63")
		)
		(pad "B64" smd rect
			(at 27.314906 4.13512)
			(size 0.381 2.1336)
			(layers "B.Cu" "B.Mask" "B.Paste")
			(net "GND")
		)
		(pad "B65" smd rect
			(at 27.915108 3.934968)
			(size 0.381 1.7272)
			(layers "B.Cu" "B.Mask" "B.Paste")
			(net "P2E_GPU_TX_C_DP")
		)
		(pad "B66" smd rect
			(at 28.515056 3.934968)
			(size 0.381 1.7272)
			(layers "B.Cu" "B.Mask" "B.Paste")
			(net "P2E_GPU_TX_C_DN")
		)
		(pad "B67" smd rect
			(at 29.115004 4.13512)
			(size 0.381 2.1336)
			(layers "B.Cu" "B.Mask" "B.Paste")
			(net "GND")
		)
		(pad "B68" smd rect
			(at 29.714952 3.934968)
			(size 0.381 1.7272)
			(layers "B.Cu" "B.Mask" "B.Paste")
			(net "HDD_LED_R_N")
		)
		(pad "B69" smd rect
			(at 30.3149 3.934968)
			(size 0.381 1.7272)
			(layers "B.Cu" "B.Mask" "B.Paste")
			(net "PCH_BEEP_R_LED")
		)
		(pad "B70" smd rect
			(at 30.915102 4.13512)
			(size 0.381 2.1336)
			(layers "B.Cu" "B.Mask" "B.Paste")
			(net "GND")
		)
		(pad "OA1" smd rect
			(at -30.39999 4.13512)
			(size 0.381 2.1336)
			(layers "B.Cu" "B.Mask" "B.Paste")
			(net "P12V_AUX")
		)
		(pad "OA2" smd rect
			(at -29.800042 3.934968)
			(size 0.381 1.7272)
			(layers "B.Cu" "B.Mask" "B.Paste")
			(net "P12V_AUX")
		)
		(pad "OA3" smd rect
			(at -29.200094 4.13512)
			(size 0.381 2.1336)
			(layers "B.Cu" "B.Mask" "B.Paste")
			(net "GND")
		)
		(pad "OA4" smd rect
			(at -28.599892 4.13512)
			(size 0.381 2.1336)
			(layers "B.Cu" "B.Mask" "B.Paste")
			(net "GND")
		)
	)
)
